(kicad_pcb
	(version 20260206)
	(generator "pcbnew")
	(generator_version "10.0")
	(general
		(thickness 1.6)
		(legacy_teardrops no)
	)
	(paper "A4")
	(title_block
		(title "01162023_DA0F0TEBIF0_F0T_Expander_BD_F_brd_V02_OCP.brd")
		(comment 1 "Grand Teton / footprints 2586-2592 of 9728")
	)
	(layers
		(0 "F.Cu" signal "TOP")
		(4 "In1.Cu" signal "GND")
		(6 "In2.Cu" signal "VCC")
		(8 "In3.Cu" signal "VCC1")
		(10 "In4.Cu" signal "GND1")
		(12 "In5.Cu" signal "IN1")
		(14 "In6.Cu" signal "GND2")
		(16 "In7.Cu" signal "IN2")
		(18 "In8.Cu" signal "GND3")
		(20 "In9.Cu" signal "IN3")
		(22 "In10.Cu" signal "GND4")
		(24 "In11.Cu" signal "IN4")
		(26 "In12.Cu" signal "GND5")
		(28 "In13.Cu" signal "IN5")
		(30 "In14.Cu" signal "GND6")
		(32 "In15.Cu" signal "IN6")
		(34 "In16.Cu" signal "GND7")
		(2 "B.Cu" signal "BOTTOM")
		(9 "F.Adhes" user "F.Adhesive")
		(11 "B.Adhes" user "B.Adhesive")
		(13 "F.Paste" user "Package Geometry/Pastemask Top")
		(15 "B.Paste" user "Package Geometry/Pastemask Bottom")
		(5 "F.SilkS" user "Ref Des/Silkscreen Top")
		(7 "B.SilkS" user "Ref Des/Silkscreen Bottom")
		(1 "F.Mask" user "Board Geometry/Soldermask Top")
		(3 "B.Mask" user "Board Geometry/Soldermask Bottom")
		(17 "Dwgs.User" user "User.Drawings")
		(19 "Cmts.User" user "User.Comments")
		(21 "Eco1.User" user "User.Eco1")
		(23 "Eco2.User" user "User.Eco2")
		(25 "Edge.Cuts" user "Board Geometry/Outline")
		(27 "Margin" user)
		(31 "F.CrtYd" user "Package Geometry/Place Bound Top")
		(29 "B.CrtYd" user "Package Geometry/Place Bound Bottom")
		(35 "F.Fab" user "Ref Des/Assembly Top")
		(33 "B.Fab" user "Ref Des/Assembly Bottom")
	)
	(footprint ""
		(layer "F.Cu")
		(at 440.350148 -306.074572 90)
		(property "Reference" "R1445"
			(at 0 0 90)
			(layer "F.SilkS")
			(hide yes)
			(effects
				(font
					(size 1.27 1.27)
				)
			)
		)
		(property "Value" ""
			(at 0 0 90)
			(layer "F.Fab")
			(effects
				(font
					(size 1.27 1.27)
				)
			)
		)
		(duplicate_pad_numbers_are_jumpers no)
		(fp_line
			(start 0.7874 -0.4064)
			(end 0.7874 0.4064)
			(stroke
				(width 0.1524)
				(type default)
			)
			(layer "F.SilkS")
		)
		(fp_line
			(start -0.7874 -0.4064)
			(end 0.7874 -0.4064)
			(stroke
				(width 0.1524)
				(type default)
			)
			(layer "F.SilkS")
		)
		(fp_line
			(start 0.7874 0.4064)
			(end -0.7874 0.4064)
			(stroke
				(width 0.1524)
				(type default)
			)
			(layer "F.SilkS")
		)
		(fp_line
			(start -0.7874 0.4064)
			(end -0.7874 -0.4064)
			(stroke
				(width 0.1524)
				(type default)
			)
			(layer "F.SilkS")
		)
		(fp_line
			(start -0.12065 -0.305054)
			(end -0.12065 -0.2794)
			(stroke
				(width 0.1)
				(type default)
			)
			(layer "F.Fab")
		)
		(fp_line
			(start -0.67945 -0.305054)
			(end -0.12065 -0.305054)
			(stroke
				(width 0.1)
				(type default)
			)
			(layer "F.Fab")
		)
		(fp_line
			(start 0.67945 -0.3048)
			(end 0.67945 0.3048)
			(stroke
				(width 0.1)
				(type default)
			)
			(layer "F.Fab")
		)
		(fp_line
			(start 0.12065 -0.3048)
			(end 0.67945 -0.3048)
			(stroke
				(width 0.1)
				(type default)
			)
			(layer "F.Fab")
		)
		(fp_line
			(start 0.12065 -0.2794)
			(end 0.12065 -0.3048)
			(stroke
				(width 0.1)
				(type default)
			)
			(layer "F.Fab")
		)
		(fp_line
			(start -0.12065 -0.2794)
			(end 0.12065 -0.2794)
			(stroke
				(width 0.1)
				(type default)
			)
			(layer "F.Fab")
		)
		(fp_line
			(start 0.120396 0.2794)
			(end -0.12065 0.2794)
			(stroke
				(width 0.1)
				(type default)
			)
			(layer "F.Fab")
		)
		(fp_line
			(start -0.12065 0.2794)
			(end -0.12065 0.3048)
			(stroke
				(width 0.1)
				(type default)
			)
			(layer "F.Fab")
		)
		(fp_line
			(start 0.67945 0.3048)
			(end 0.120396 0.3048)
			(stroke
				(width 0.1)
				(type default)
			)
			(layer "F.Fab")
		)
		(fp_line
			(start 0.120396 0.3048)
			(end 0.120396 0.2794)
			(stroke
				(width 0.1)
				(type default)
			)
			(layer "F.Fab")
		)
		(fp_line
			(start -0.12065 0.3048)
			(end -0.67945 0.3048)
			(stroke
				(width 0.1)
				(type default)
			)
			(layer "F.Fab")
		)
		(fp_line
			(start -0.67945 0.3048)
			(end -0.67945 -0.305054)
			(stroke
				(width 0.1)
				(type default)
			)
			(layer "F.Fab")
		)
		(pad "1" smd circle
			(at -0.40005 0 90)
			(size 0 0)
			(layers "F.Cu" "F.Mask" "F.Paste")
			(net "PEX3_SPARE6")
		)
		(pad "2" smd circle
			(at 0.40005 0 90)
			(size 0 0)
			(layers "F.Cu" "F.Mask" "F.Paste")
			(net "P1V8_PEX")
		)
	)
	(footprint ""
		(layer "F.Cu")
		(at 165.76802 -19.453098)
		(property "Reference" "R1668"
			(at 0 0 0)
			(layer "F.SilkS")
			(hide yes)
			(effects
				(font
					(size 1.27 1.27)
				)
			)
		)
		(property "Value" ""
			(at 0 0 0)
			(layer "F.Fab")
			(effects
				(font
					(size 1.27 1.27)
				)
			)
		)
		(duplicate_pad_numbers_are_jumpers no)
		(fp_line
			(start -0.7874 -0.4064)
			(end 0.7874 -0.4064)
			(stroke
				(width 0.1524)
				(type default)
			)
			(layer "F.SilkS")
		)
		(fp_line
			(start -0.7874 0.4064)
			(end -0.7874 -0.4064)
			(stroke
				(width 0.1524)
				(type default)
			)
			(layer "F.SilkS")
		)
		(fp_line
			(start 0.7874 -0.4064)
			(end 0.7874 0.4064)
			(stroke
				(width 0.1524)
				(type default)
			)
			(layer "F.SilkS")
		)
		(fp_line
			(start 0.7874 0.4064)
			(end -0.7874 0.4064)
			(stroke
				(width 0.1524)
				(type default)
			)
			(layer "F.SilkS")
		)
		(fp_line
			(start -0.67945 -0.305054)
			(end -0.12065 -0.305054)
			(stroke
				(width 0.1)
				(type default)
			)
			(layer "F.Fab")
		)
		(fp_line
			(start -0.67945 0.3048)
			(end -0.67945 -0.305054)
			(stroke
				(width 0.1)
				(type default)
			)
			(layer "F.Fab")
		)
		(fp_line
			(start -0.12065 -0.305054)
			(end -0.12065 -0.2794)
			(stroke
				(width 0.1)
				(type default)
			)
			(layer "F.Fab")
		)
		(fp_line
			(start -0.12065 -0.2794)
			(end 0.12065 -0.2794)
			(stroke
				(width 0.1)
				(type default)
			)
			(layer "F.Fab")
		)
		(fp_line
			(start -0.12065 0.2794)
			(end -0.12065 0.3048)
			(stroke
				(width 0.1)
				(type default)
			)
			(layer "F.Fab")
		)
		(fp_line
			(start -0.12065 0.3048)
			(end -0.67945 0.3048)
			(stroke
				(width 0.1)
				(type default)
			)
			(layer "F.Fab")
		)
		(fp_line
			(start 0.120396 0.2794)
			(end -0.12065 0.2794)
			(stroke
				(width 0.1)
				(type default)
			)
			(layer "F.Fab")
		)
		(fp_line
			(start 0.120396 0.3048)
			(end 0.120396 0.2794)
			(stroke
				(width 0.1)
				(type default)
			)
			(layer "F.Fab")
		)
		(fp_line
			(start 0.12065 -0.3048)
			(end 0.67945 -0.3048)
			(stroke
				(width 0.1)
				(type default)
			)
			(layer "F.Fab")
		)
		(fp_line
			(start 0.12065 -0.2794)
			(end 0.12065 -0.3048)
			(stroke
				(width 0.1)
				(type default)
			)
			(layer "F.Fab")
		)
		(fp_line
			(start 0.67945 -0.3048)
			(end 0.67945 0.3048)
			(stroke
				(width 0.1)
				(type default)
			)
			(layer "F.Fab")
		)
		(fp_line
			(start 0.67945 0.3048)
			(end 0.120396 0.3048)
			(stroke
				(width 0.1)
				(type default)
			)
			(layer "F.Fab")
		)
		(pad "1" smd circle
			(at -0.40005 0)
			(size 0 0)
			(layers "F.Cu" "F.Mask" "F.Paste")
			(net "SMB_ISO_SSD5_R_SDA")
		)
		(pad "2" smd circle
			(at 0.40005 0)
			(size 0 0)
			(layers "F.Cu" "F.Mask" "F.Paste")
			(net "SMB_ISO_SSD5_SDA")
		)
	)
	(footprint ""
		(layer "F.Cu")
		(at 358.013 -213.36 180)
		(property "Reference" "R4094"
			(at 0 0 180)
			(layer "F.SilkS")
			(hide yes)
			(effects
				(font
					(size 1.27 1.27)
				)
			)
		)
		(property "Value" ""
			(at 0 0 180)
			(layer "F.Fab")
			(effects
				(font
					(size 1.27 1.27)
				)
			)
		)
		(duplicate_pad_numbers_are_jumpers no)
		(fp_line
			(start 0.7874 0.4064)
			(end -0.7874 0.4064)
			(stroke
				(width 0.1524)
				(type default)
			)
			(layer "F.SilkS")
		)
		(fp_line
			(start 0.7874 -0.4064)
			(end 0.7874 0.4064)
			(stroke
				(width 0.1524)
				(type default)
			)
			(layer "F.SilkS")
		)
		(fp_line
			(start -0.7874 0.4064)
			(end -0.7874 -0.4064)
			(stroke
				(width 0.1524)
				(type default)
			)
			(layer "F.SilkS")
		)
		(fp_line
			(start -0.7874 -0.4064)
			(end 0.7874 -0.4064)
			(stroke
				(width 0.1524)
				(type default)
			)
			(layer "F.SilkS")
		)
		(fp_line
			(start 0.67945 0.3048)
			(end 0.120396 0.3048)
			(stroke
				(width 0.1)
				(type default)
			)
			(layer "F.Fab")
		)
		(fp_line
			(start 0.67945 -0.3048)
			(end 0.67945 0.3048)
			(stroke
				(width 0.1)
				(type default)
			)
			(layer "F.Fab")
		)
		(fp_line
			(start 0.12065 -0.2794)
			(end 0.12065 -0.3048)
			(stroke
				(width 0.1)
				(type default)
			)
			(layer "F.Fab")
		)
		(fp_line
			(start 0.12065 -0.3048)
			(end 0.67945 -0.3048)
			(stroke
				(width 0.1)
				(type default)
			)
			(layer "F.Fab")
		)
		(fp_line
			(start 0.120396 0.3048)
			(end 0.120396 0.2794)
			(stroke
				(width 0.1)
				(type default)
			)
			(layer "F.Fab")
		)
		(fp_line
			(start 0.120396 0.2794)
			(end -0.12065 0.2794)
			(stroke
				(width 0.1)
				(type default)
			)
			(layer "F.Fab")
		)
		(fp_line
			(start -0.12065 0.3048)
			(end -0.67945 0.3048)
			(stroke
				(width 0.1)
				(type default)
			)
			(layer "F.Fab")
		)
		(fp_line
			(start -0.12065 0.2794)
			(end -0.12065 0.3048)
			(stroke
				(width 0.1)
				(type default)
			)
			(layer "F.Fab")
		)
		(fp_line
			(start -0.12065 -0.2794)
			(end 0.12065 -0.2794)
			(stroke
				(width 0.1)
				(type default)
			)
			(layer "F.Fab")
		)
		(fp_line
			(start -0.12065 -0.305054)
			(end -0.12065 -0.2794)
			(stroke
				(width 0.1)
				(type default)
			)
			(layer "F.Fab")
		)
		(fp_line
			(start -0.67945 0.3048)
			(end -0.67945 -0.305054)
			(stroke
				(width 0.1)
				(type default)
			)
			(layer "F.Fab")
		)
		(fp_line
			(start -0.67945 -0.305054)
			(end -0.12065 -0.305054)
			(stroke
				(width 0.1)
				(type default)
			)
			(layer "F.Fab")
		)
		(pad "1" smd circle
			(at -0.40005 0 180)
			(size 0 0)
			(layers "F.Cu" "F.Mask" "F.Paste")
			(net "PRSNT_NIC2_FPGA_R_N")
		)
		(pad "2" smd circle
			(at 0.40005 0 180)
			(size 0 0)
			(layers "F.Cu" "F.Mask" "F.Paste")
			(net "PRSNT_NIC2_FPGA_N")
		)
	)
	(footprint ""
		(layer "F.Cu")
		(at 30.081982 -299.391832 180)
		(property "Reference" "C3031"
			(at 0 0 180)
			(layer "F.SilkS")
			(hide yes)
			(effects
				(font
					(size 1.27 1.27)
				)
			)
		)
		(property "Value" ""
			(at 0 0 180)
			(layer "F.Fab")
			(effects
				(font
					(size 1.27 1.27)
				)
			)
		)
		(duplicate_pad_numbers_are_jumpers no)
		(fp_line
			(start 1.2954 0.5842)
			(end -1.2954 0.5842)
			(stroke
				(width 0.1524)
				(type default)
			)
			(layer "F.SilkS")
		)
		(fp_line
			(start 1.2954 -0.5842)
			(end 1.2954 0.5842)
			(stroke
				(width 0.1524)
				(type default)
			)
			(layer "F.SilkS")
		)
		(fp_line
			(start -1.2954 0.5842)
			(end -1.2954 -0.5842)
			(stroke
				(width 0.1524)
				(type default)
			)
			(layer "F.SilkS")
		)
		(fp_line
			(start -1.2954 -0.5842)
			(end 1.2954 -0.5842)
			(stroke
				(width 0.1524)
				(type default)
			)
			(layer "F.SilkS")
		)
		(fp_line
			(start 1.1938 0.4064)
			(end 0.8636 0.4064)
			(stroke
				(width 0.1)
				(type default)
			)
			(layer "F.Fab")
		)
		(fp_line
			(start 1.1938 -0.4064)
			(end 1.1938 0.4064)
			(stroke
				(width 0.1)
				(type default)
			)
			(layer "F.Fab")
		)
		(fp_line
			(start 0.8636 0.4572)
			(end -0.8636 0.4572)
			(stroke
				(width 0.1)
				(type default)
			)
			(layer "F.Fab")
		)
		(fp_line
			(start 0.8636 0.4064)
			(end 0.8636 0.4572)
			(stroke
				(width 0.1)
				(type default)
			)
			(layer "F.Fab")
		)
		(fp_line
			(start 0.8636 -0.4064)
			(end 1.1938 -0.4064)
			(stroke
				(width 0.1)
				(type default)
			)
			(layer "F.Fab")
		)
		(fp_line
			(start 0.8636 -0.4572)
			(end 0.8636 -0.4064)
			(stroke
				(width 0.1)
				(type default)
			)
			(layer "F.Fab")
		)
		(fp_line
			(start -0.8636 0.4572)
			(end -0.8636 0.4064)
			(stroke
				(width 0.1)
				(type default)
			)
			(layer "F.Fab")
		)
		(fp_line
			(start -0.8636 0.4064)
			(end -1.1938 0.4064)
			(stroke
				(width 0.1)
				(type default)
			)
			(layer "F.Fab")
		)
		(fp_line
			(start -0.8636 -0.4064)
			(end -0.8636 -0.4572)
			(stroke
				(width 0.1)
				(type default)
			)
			(layer "F.Fab")
		)
		(fp_line
			(start -0.8636 -0.4572)
			(end 0.8636 -0.4572)
			(stroke
				(width 0.1)
				(type default)
			)
			(layer "F.Fab")
		)
		(fp_line
			(start -1.1938 0.4064)
			(end -1.1938 -0.4064)
			(stroke
				(width 0.1)
				(type default)
			)
			(layer "F.Fab")
		)
		(fp_line
			(start -1.1938 -0.4064)
			(end -0.8636 -0.4064)
			(stroke
				(width 0.1)
				(type default)
			)
			(layer "F.Fab")
		)
		(pad "1" smd rect
			(at -0.7366 0 90)
			(size 0.7112 0.8128)
			(layers "F.Cu" "F.Mask" "F.Paste")
			(net "PCEPLL1_VDDA18_PEX0_R")
		)
		(pad "2" smd rect
			(at 0.7366 0 90)
			(size 0.7112 0.8128)
			(layers "F.Cu" "F.Mask" "F.Paste")
			(net "GND")
		)
	)
	(footprint ""
		(layer "F.Cu")
		(at 104.6734 -202.466956 90)
		(property "Reference" "R6632"
			(at 0 0 90)
			(layer "F.SilkS")
			(hide yes)
			(effects
				(font
					(size 1.27 1.27)
				)
			)
		)
		(property "Value" ""
			(at 0 0 90)
			(layer "F.Fab")
			(effects
				(font
					(size 1.27 1.27)
				)
			)
		)
		(duplicate_pad_numbers_are_jumpers no)
		(fp_line
			(start 0.7874 -0.4064)
			(end 0.7874 0.4064)
			(stroke
				(width 0.1524)
				(type default)
			)
			(layer "F.SilkS")
		)
		(fp_line
			(start -0.7874 -0.4064)
			(end 0.7874 -0.4064)
			(stroke
				(width 0.1524)
				(type default)
			)
			(layer "F.SilkS")
		)
		(fp_line
			(start 0.7874 0.4064)
			(end -0.7874 0.4064)
			(stroke
				(width 0.1524)
				(type default)
			)
			(layer "F.SilkS")
		)
		(fp_line
			(start -0.7874 0.4064)
			(end -0.7874 -0.4064)
			(stroke
				(width 0.1524)
				(type default)
			)
			(layer "F.SilkS")
		)
		(fp_line
			(start -0.12065 -0.305054)
			(end -0.12065 -0.2794)
			(stroke
				(width 0.1)
				(type default)
			)
			(layer "F.Fab")
		)
		(fp_line
			(start -0.67945 -0.305054)
			(end -0.12065 -0.305054)
			(stroke
				(width 0.1)
				(type default)
			)
			(layer "F.Fab")
		)
		(fp_line
			(start 0.67945 -0.3048)
			(end 0.67945 0.3048)
			(stroke
				(width 0.1)
				(type default)
			)
			(layer "F.Fab")
		)
		(fp_line
			(start 0.12065 -0.3048)
			(end 0.67945 -0.3048)
			(stroke
				(width 0.1)
				(type default)
			)
			(layer "F.Fab")
		)
		(fp_line
			(start 0.12065 -0.2794)
			(end 0.12065 -0.3048)
			(stroke
				(width 0.1)
				(type default)
			)
			(layer "F.Fab")
		)
		(fp_line
			(start -0.12065 -0.2794)
			(end 0.12065 -0.2794)
			(stroke
				(width 0.1)
				(type default)
			)
			(layer "F.Fab")
		)
		(fp_line
			(start 0.120396 0.2794)
			(end -0.12065 0.2794)
			(stroke
				(width 0.1)
				(type default)
			)
			(layer "F.Fab")
		)
		(fp_line
			(start -0.12065 0.2794)
			(end -0.12065 0.3048)
			(stroke
				(width 0.1)
				(type default)
			)
			(layer "F.Fab")
		)
		(fp_line
			(start 0.67945 0.3048)
			(end 0.120396 0.3048)
			(stroke
				(width 0.1)
				(type default)
			)
			(layer "F.Fab")
		)
		(fp_line
			(start 0.120396 0.3048)
			(end 0.120396 0.2794)
			(stroke
				(width 0.1)
				(type default)
			)
			(layer "F.Fab")
		)
		(fp_line
			(start -0.12065 0.3048)
			(end -0.67945 0.3048)
			(stroke
				(width 0.1)
				(type default)
			)
			(layer "F.Fab")
		)
		(fp_line
			(start -0.67945 0.3048)
			(end -0.67945 -0.305054)
			(stroke
				(width 0.1)
				(type default)
			)
			(layer "F.Fab")
		)
		(pad "1" smd circle
			(at -0.40005 0 90)
			(size 0 0)
			(layers "F.Cu" "F.Mask" "F.Paste")
			(net "UART_PEX0_CLI_CP2108_RX")
		)
		(pad "2" smd circle
			(at 0.40005 0 90)
			(size 0 0)
			(layers "F.Cu" "F.Mask" "F.Paste")
			(net "UART_PEX0_CLI_R_RX")
		)
	)
	(footprint ""
		(layer "F.Cu")
		(at 86.906608 -306.074572 90)
		(property "Reference" "R3894"
			(at 0 0 90)
			(layer "F.SilkS")
			(hide yes)
			(effects
				(font
					(size 1.27 1.27)
				)
			)
		)
		(property "Value" ""
			(at 0 0 90)
			(layer "F.Fab")
			(effects
				(font
					(size 1.27 1.27)
				)
			)
		)
		(duplicate_pad_numbers_are_jumpers no)
		(fp_line
			(start 0.7874 -0.4064)
			(end 0.7874 0.4064)
			(stroke
				(width 0.1524)
				(type default)
			)
			(layer "F.SilkS")
		)
		(fp_line
			(start -0.7874 -0.4064)
			(end 0.7874 -0.4064)
			(stroke
				(width 0.1524)
				(type default)
			)
			(layer "F.SilkS")
		)
		(fp_line
			(start 0.7874 0.4064)
			(end -0.7874 0.4064)
			(stroke
				(width 0.1524)
				(type default)
			)
			(layer "F.SilkS")
		)
		(fp_line
			(start -0.7874 0.4064)
			(end -0.7874 -0.4064)
			(stroke
				(width 0.1524)
				(type default)
			)
			(layer "F.SilkS")
		)
		(fp_line
			(start -0.12065 -0.305054)
			(end -0.12065 -0.2794)
			(stroke
				(width 0.1)
				(type default)
			)
			(layer "F.Fab")
		)
		(fp_line
			(start -0.67945 -0.305054)
			(end -0.12065 -0.305054)
			(stroke
				(width 0.1)
				(type default)
			)
			(layer "F.Fab")
		)
		(fp_line
			(start 0.67945 -0.3048)
			(end 0.67945 0.3048)
			(stroke
				(width 0.1)
				(type default)
			)
			(layer "F.Fab")
		)
		(fp_line
			(start 0.12065 -0.3048)
			(end 0.67945 -0.3048)
			(stroke
				(width 0.1)
				(type default)
			)
			(layer "F.Fab")
		)
		(fp_line
			(start 0.12065 -0.2794)
			(end 0.12065 -0.3048)
			(stroke
				(width 0.1)
				(type default)
			)
			(layer "F.Fab")
		)
		(fp_line
			(start -0.12065 -0.2794)
			(end 0.12065 -0.2794)
			(stroke
				(width 0.1)
				(type default)
			)
			(layer "F.Fab")
		)
		(fp_line
			(start 0.120396 0.2794)
			(end -0.12065 0.2794)
			(stroke
				(width 0.1)
				(type default)
			)
			(layer "F.Fab")
		)
		(fp_line
			(start -0.12065 0.2794)
			(end -0.12065 0.3048)
			(stroke
				(width 0.1)
				(type default)
			)
			(layer "F.Fab")
		)
		(fp_line
			(start 0.67945 0.3048)
			(end 0.120396 0.3048)
			(stroke
				(width 0.1)
				(type default)
			)
			(layer "F.Fab")
		)
		(fp_line
			(start 0.120396 0.3048)
			(end 0.120396 0.2794)
			(stroke
				(width 0.1)
				(type default)
			)
			(layer "F.Fab")
		)
		(fp_line
			(start -0.12065 0.3048)
			(end -0.67945 0.3048)
			(stroke
				(width 0.1)
				(type default)
			)
			(layer "F.Fab")
		)
		(fp_line
			(start -0.67945 0.3048)
			(end -0.67945 -0.305054)
			(stroke
				(width 0.1)
				(type default)
			)
			(layer "F.Fab")
		)
		(pad "1" smd circle
			(at -0.40005 0 90)
			(size 0 0)
			(layers "F.Cu" "F.Mask" "F.Paste")
			(net "SMB_PEX0_SLAVE_SCL")
		)
		(pad "2" smd circle
			(at 0.40005 0 90)
			(size 0 0)
			(layers "F.Cu" "F.Mask" "F.Paste")
			(net "SMB_PEX0_R_SCL")
		)
	)
	(footprint ""
		(layer "F.Cu")
		(at 278.112982 -350.098614 90)
		(property "Reference" "C2350"
			(at 0 0 90)
			(layer "F.SilkS")
			(hide yes)
			(effects
				(font
					(size 1.27 1.27)
				)
			)
		)
		(property "Value" ""
			(at 0 0 90)
			(layer "F.Fab")
			(effects
				(font
					(size 1.27 1.27)
				)
			)
		)
		(duplicate_pad_numbers_are_jumpers no)
		(fp_line
			(start 0.299974 -0.150114)
			(end 0.299974 0.150114)
			(stroke
				(width 0.1)
				(type default)
			)
			(layer "F.Fab")
		)
		(fp_line
			(start -0.299974 -0.150114)
			(end 0.299974 -0.150114)
			(stroke
				(width 0.1)
				(type default)
			)
			(layer "F.Fab")
		)
		(fp_line
			(start 0.299974 0.150114)
			(end -0.299974 0.150114)
			(stroke
				(width 0.1)
				(type default)
			)
			(layer "F.Fab")
		)
		(fp_line
			(start -0.299974 0.150114)
			(end -0.299974 -0.150114)
			(stroke
				(width 0.1)
				(type default)
			)
			(layer "F.Fab")
		)
		(pad "1" smd rect
			(at -0.2667 0 90)
			(size 0.3048 0.381)
			(layers "F.Cu" "F.Mask" "F.Paste")
			(net "P5E_PEX2_STN4_TX_DN<75>")
		)
		(pad "2" smd rect
			(at 0.2667 0 90)
			(size 0.3048 0.381)
			(layers "F.Cu" "F.Mask" "F.Paste")
			(net "P5E_PEX2_STN4_TX_C_DN<75>")
		)
	)
)
